(kicad_pcb
	(version 20240108)
	(generator "pcbnew")
	(generator_version "8.0")
	(general
		(thickness 1.586)
		(legacy_teardrops no)
	)
	(paper "A4")
	(title_block
		(title "GMSL Serializer")
		(date "2024-11-27")
		(rev "1.1.1")
		(company "Antmicro Ltd")
		(comment 1 "www.antmicro.com")
		(comment 9 "footprints 32-33 of 117")
	)
	(layers
		(0 "F.Cu" signal)
		(1 "In1.Cu" power)
		(2 "In2.Cu" power)
		(31 "B.Cu" signal)
		(32 "B.Adhes" user "B.Adhesive")
		(33 "F.Adhes" user "F.Adhesive")
		(34 "B.Paste" user)
		(35 "F.Paste" user)
		(36 "B.SilkS" user "B.Silkscreen")
		(37 "F.SilkS" user "F.Silkscreen")
		(38 "B.Mask" user)
		(39 "F.Mask" user)
		(40 "Dwgs.User" user "User.Drawings")
		(41 "Cmts.User" user "User.Comments")
		(42 "Eco1.User" user "User.Eco1")
		(43 "Eco2.User" user "User.Eco2")
		(44 "Edge.Cuts" user)
		(45 "Margin" user)
		(46 "B.CrtYd" user "B.Courtyard")
		(47 "F.CrtYd" user "F.Courtyard")
		(48 "B.Fab" user)
		(49 "F.Fab" user)
	)
	(footprint "antmicro-footprints:Conn_FFC_WE_68715014x22"
		(locked yes)
		(layer "F.Cu")
		(at 126.2 101.85 -90)
		(property "Reference" "J1"
			(at -16.45 0 180)
			(layer "F.SilkS")
			(effects
				(font
					(size 0.7 0.7)
					(thickness 0.15)
				)
				(justify right bottom)
			)
		)
		(property "Value" "Conn_FFC_WE_68715014022"
			(at 0 4.5 90)
			(layer "F.Fab")
			(effects
				(font
					(size 0.7 0.7)
					(thickness 0.15)
				)
				(justify right bottom)
			)
		)
		(property "Footprint" "antmicro-footprints:Conn_FFC_WE_68715014x22"
			(at 0 0 -90)
			(layer "F.Fab")
			(hide yes)
			(effects
				(font
					(size 1.27 1.27)
					(thickness 0.15)
				)
			)
		)
		(property "Datasheet" "https://www.we-online.com/components/products/datasheet/68715014022.pdf"
			(at 0 0 -90)
			(layer "F.Fab")
			(hide yes)
			(effects
				(font
					(size 1.27 1.27)
					(thickness 0.15)
				)
			)
		)
		(property "Author" "Antmicro"
			(at 24.35 228.05 0)
			(layer "F.Fab")
			(hide yes)
			(effects
				(font
					(size 1 1)
					(thickness 0.15)
				)
			)
		)
		(property "License" "Apache-2.0"
			(at 24.35 228.05 0)
			(layer "F.Fab")
			(hide yes)
			(effects
				(font
					(size 1 1)
					(thickness 0.15)
				)
			)
		)
		(property "MPN" "68715014022"
			(at 24.35 228.05 0)
			(layer "F.Fab")
			(hide yes)
			(effects
				(font
					(size 1 1)
					(thickness 0.15)
				)
			)
		)
		(property "Manufacturer" "Würth Elektronik"
			(at 24.35 228.05 0)
			(layer "F.Fab")
			(hide yes)
			(effects
				(font
					(size 1 1)
					(thickness 0.15)
				)
			)
		)
		(sheetname "CSI Connector")
		(sheetfile "CSI.kicad_sch")
		(attr smd)
		(fp_line
			(start -15.85 2.7)
			(end -15.85 -2.15)
			(stroke
				(width 0.15)
				(type solid)
			)
			(layer "F.SilkS")
		)
		(fp_line
			(start 15.85 2.7)
			(end -15.85 2.7)
			(stroke
				(width 0.15)
				(type solid)
			)
			(layer "F.SilkS")
		)
		(fp_line
			(start 15.85 2.7)
			(end 15.85 -2.15)
			(stroke
				(width 0.15)
				(type solid)
			)
			(layer "F.SilkS")
		)
		(fp_line
			(start -15.85 -2.15)
			(end -12.5 -2.15)
			(stroke
				(width 0.15)
				(type solid)
			)
			(layer "F.SilkS")
		)
		(fp_line
			(start -12.5 -2.15)
			(end -12.5 -2.976)
			(stroke
				(width 0.15)
				(type solid)
			)
			(layer "F.SilkS")
		)
		(fp_line
			(start 12.499 -2.15)
			(end 12.499 -2.976)
			(stroke
				(width 0.15)
				(type solid)
			)
			(layer "F.SilkS")
		)
		(fp_line
			(start 15.85 -2.15)
			(end 12.499 -2.15)
			(stroke
				(width 0.15)
				(type solid)
			)
			(layer "F.SilkS")
		)
		(fp_line
			(start -12.5 -2.976)
			(end 12.499 -2.976)
			(stroke
				(width 0.15)
				(type solid)
			)
			(layer "F.SilkS")
		)
		(fp_circle
			(center -12.9 -2.9)
			(end -12.85 -2.85)
			(stroke
				(width 0.15)
				(type solid)
			)
			(fill solid)
			(layer "F.SilkS")
		)
		(fp_rect
			(start -16.2 -3.25)
			(end 16.2 3.55)
			(stroke
				(width 0.05)
				(type solid)
			)
			(fill none)
			(layer "F.CrtYd")
		)
		(fp_text user "License: Apache-2.0"
			(at -16.2 7.9 90)
			(layer "F.Fab")
			(hide yes)
			(effects
				(font
					(size 0.7 0.7)
					(thickness 0.15)
				)
				(justify right bottom)
			)
		)
		(fp_text user "${REFERENCE}"
			(at -16.2 5.9 90)
			(layer "F.Fab")
			(hide yes)
			(effects
				(font
					(size 0.7 0.7)
					(thickness 0.15)
				)
				(justify right bottom)
			)
		)
		(fp_text user "Author: Antmicro"
			(at -16.2 6.9 90)
			(layer "F.Fab")
			(hide yes)
			(effects
				(font
					(size 0.7 0.7)
					(thickness 0.15)
				)
				(justify right bottom)
			)
		)
		(pad "1" smd roundrect
			(at -12.25 -2.15 270)
			(size 0.3 1.2)
			(layers "F.Cu" "F.Paste" "F.Mask")
			(roundrect_rratio 0.25)
			(net 19 "unconnected-(J1-Pad1)")
			(pintype "passive+no_connect")
		)
		(pad "2" smd roundrect
			(at -11.75 -2.15 270)
			(size 0.3 1.2)
			(layers "F.Cu" "F.Paste" "F.Mask")
			(roundrect_rratio 0.25)
			(net 20 "unconnected-(J1-Pad2)")
			(pintype "passive+no_connect")
		)
		(pad "3" smd roundrect
			(at -11.25 -2.15 270)
			(size 0.3 1.2)
			(layers "F.Cu" "F.Paste" "F.Mask")
			(roundrect_rratio 0.25)
			(net 21 "unconnected-(J1-Pad3)")
			(pintype "passive+no_connect")
		)
		(pad "4" smd roundrect
			(at -10.75 -2.15 270)
			(size 0.3 1.2)
			(layers "F.Cu" "F.Paste" "F.Mask")
			(roundrect_rratio 0.25)
			(net 22 "unconnected-(J1-Pad4)")
			(pintype "passive+no_connect")
		)
		(pad "5" smd roundrect
			(at -10.25 -2.15 270)
			(size 0.3 1.2)
			(layers "F.Cu" "F.Paste" "F.Mask")
			(roundrect_rratio 0.25)
			(net 23 "unconnected-(J1-Pad5)")
			(pintype "passive+no_connect")
		)
		(pad "6" smd roundrect
			(at -9.75 -2.15 270)
			(size 0.3 1.2)
			(layers "F.Cu" "F.Paste" "F.Mask")
			(roundrect_rratio 0.25)
			(net 24 "unconnected-(J1-Pad6)")
			(pintype "passive+no_connect")
		)
		(pad "7" smd roundrect
			(at -9.25 -2.15 270)
			(size 0.3 1.2)
			(layers "F.Cu" "F.Paste" "F.Mask")
			(roundrect_rratio 0.25)
			(net 25 "unconnected-(J1-Pad7)")
			(pintype "passive+no_connect")
		)
		(pad "8" smd roundrect
			(at -8.75 -2.15 270)
			(size 0.3 1.2)
			(layers "F.Cu" "F.Paste" "F.Mask")
			(roundrect_rratio 0.25)
			(net 26 "unconnected-(J1-Pad8)")
			(pintype "passive+no_connect")
		)
		(pad "9" smd roundrect
			(at -8.25 -2.15 270)
			(size 0.3 1.2)
			(layers "F.Cu" "F.Paste" "F.Mask")
			(roundrect_rratio 0.25)
			(net 1 "GND")
			(pintype "passive")
		)
		(pad "10" smd roundrect
			(at -7.75 -2.15 270)
			(size 0.3 1.2)
			(layers "F.Cu" "F.Paste" "F.Mask")
			(roundrect_rratio 0.25)
			(net 27 "unconnected-(J1-Pad10)")
			(pintype "passive+no_connect")
		)
		(pad "11" smd roundrect
			(at -7.25 -2.15 270)
			(size 0.3 1.2)
			(layers "F.Cu" "F.Paste" "F.Mask")
			(roundrect_rratio 0.25)
			(net 28 "unconnected-(J1-Pad11)")
			(pintype "passive+no_connect")
		)
		(pad "12" smd roundrect
			(at -6.75 -2.15 270)
			(size 0.3 1.2)
			(layers "F.Cu" "F.Paste" "F.Mask")
			(roundrect_rratio 0.25)
			(net 1 "GND")
			(pintype "passive")
		)
		(pad "13" smd roundrect
			(at -6.25 -2.15 270)
			(size 0.3 1.2)
			(layers "F.Cu" "F.Paste" "F.Mask")
			(roundrect_rratio 0.25)
			(net 29 "unconnected-(J1-Pad13)")
			(pintype "passive+no_connect")
		)
		(pad "14" smd roundrect
			(at -5.75 -2.15 270)
			(size 0.3 1.2)
			(layers "F.Cu" "F.Paste" "F.Mask")
			(roundrect_rratio 0.25)
			(net 30 "unconnected-(J1-Pad14)")
			(pintype "passive+no_connect")
		)
		(pad "15" smd roundrect
			(at -5.25 -2.15 270)
			(size 0.3 1.2)
			(layers "F.Cu" "F.Paste" "F.Mask")
			(roundrect_rratio 0.25)
			(net 1 "GND")
			(pintype "passive")
		)
		(pad "16" smd roundrect
			(at -4.75 -2.15 270)
			(size 0.3 1.2)
			(layers "F.Cu" "F.Paste" "F.Mask")
			(roundrect_rratio 0.25)
			(net 31 "unconnected-(J1-Pad16)")
			(pintype "passive+no_connect")
		)
		(pad "17" smd roundrect
			(at -4.25 -2.15 270)
			(size 0.3 1.2)
			(layers "F.Cu" "F.Paste" "F.Mask")
			(roundrect_rratio 0.25)
			(net 32 "unconnected-(J1-Pad17)")
			(pintype "passive+no_connect")
		)
		(pad "18" smd roundrect
			(at -3.75 -2.15 270)
			(size 0.3 1.2)
			(layers "F.Cu" "F.Paste" "F.Mask")
			(roundrect_rratio 0.25)
			(net 1 "GND")
			(pintype "passive")
		)
		(pad "19" smd roundrect
			(at -3.25 -2.15 270)
			(size 0.3 1.2)
			(layers "F.Cu" "F.Paste" "F.Mask")
			(roundrect_rratio 0.25)
			(net 40 "/CSI Connector/CSI.D3_N")
			(pintype "passive")
		)
		(pad "20" smd roundrect
			(at -2.75 -2.15 270)
			(size 0.3 1.2)
			(layers "F.Cu" "F.Paste" "F.Mask")
			(roundrect_rratio 0.25)
			(net 41 "/CSI Connector/CSI.D3_P")
			(pintype "passive")
		)
		(pad "21" smd roundrect
			(at -2.25 -2.15 270)
			(size 0.3 1.2)
			(layers "F.Cu" "F.Paste" "F.Mask")
			(roundrect_rratio 0.25)
			(net 42 "/CSI Connector/CSI.D2_N")
			(pintype "passive")
		)
		(pad "22" smd roundrect
			(at -1.75 -2.15 270)
			(size 0.3 1.2)
			(layers "F.Cu" "F.Paste" "F.Mask")
			(roundrect_rratio 0.25)
			(net 44 "/CSI Connector/CSI.D2_P")
			(pintype "passive")
		)
		(pad "23" smd roundrect
			(at -1.25 -2.15 270)
			(size 0.3 1.2)
			(layers "F.Cu" "F.Paste" "F.Mask")
			(roundrect_rratio 0.25)
			(net 50 "/CSI Connector/CSI.D1_N")
			(pintype "passive")
		)
		(pad "24" smd roundrect
			(at -0.75 -2.15 270)
			(size 0.3 1.2)
			(layers "F.Cu" "F.Paste" "F.Mask")
			(roundrect_rratio 0.25)
			(net 51 "/CSI Connector/CSI.D1_P")
			(pintype "passive")
		)
		(pad "25" smd roundrect
			(at -0.25 -2.15 270)
			(size 0.3 1.2)
			(layers "F.Cu" "F.Paste" "F.Mask")
			(roundrect_rratio 0.25)
			(net 56 "/CSI Connector/CSI.D0_N")
			(pintype "passive")
		)
		(pad "26" smd roundrect
			(at 0.248 -2.15 270)
			(size 0.3 1.2)
			(layers "F.Cu" "F.Paste" "F.Mask")
			(roundrect_rratio 0.25)
			(net 57 "/CSI Connector/CSI.D0_P")
			(pintype "passive")
		)
		(pad "27" smd roundrect
			(at 0.748 -2.15 270)
			(size 0.3 1.2)
			(layers "F.Cu" "F.Paste" "F.Mask")
			(roundrect_rratio 0.25)
			(net 1 "GND")
			(pintype "passive")
		)
		(pad "28" smd roundrect
			(at 1.249 -2.15 270)
			(size 0.3 1.2)
			(layers "F.Cu" "F.Paste" "F.Mask")
			(roundrect_rratio 0.25)
			(net 61 "/CSI Connector/CSI.CLK_N")
			(pintype "passive")
		)
		(pad "29" smd roundrect
			(at 1.749 -2.15 270)
			(size 0.3 1.2)
			(layers "F.Cu" "F.Paste" "F.Mask")
			(roundrect_rratio 0.25)
			(net 80 "/CSI Connector/CSI.CLK_P")
			(pintype "passive")
		)
		(pad "30" smd roundrect
			(at 2.249 -2.15 270)
			(size 0.3 1.2)
			(layers "F.Cu" "F.Paste" "F.Mask")
			(roundrect_rratio 0.25)
			(net 1 "GND")
			(pintype "passive")
		)
		(pad "31" smd roundrect
			(at 2.749 -2.15 270)
			(size 0.3 1.2)
			(layers "F.Cu" "F.Paste" "F.Mask")
			(roundrect_rratio 0.25)
			(net 43 "unconnected-(J1-Pad31)")
			(pintype "passive+no_connect")
		)
		(pad "32" smd roundrect
			(at 3.249 -2.15 270)
			(size 0.3 1.2)
			(layers "F.Cu" "F.Paste" "F.Mask")
			(roundrect_rratio 0.25)
			(net 38 "/CSI Connector/GPIO3")
			(pintype "passive")
		)
		(pad "33" smd roundrect
			(at 3.749 -2.15 270)
			(size 0.3 1.2)
			(layers "F.Cu" "F.Paste" "F.Mask")
			(roundrect_rratio 0.25)
			(net 45 "unconnected-(J1-Pad33)")
			(pintype "passive+no_connect")
		)
		(pad "34" smd roundrect
			(at 4.248 -2.15 270)
			(size 0.3 1.2)
			(layers "F.Cu" "F.Paste" "F.Mask")
			(roundrect_rratio 0.25)
			(net 39 "/CSI Connector/GPIO4_1V8")
			(pintype "passive")
		)
		(pad "35" smd roundrect
			(at 4.748 -2.15 270)
			(size 0.3 1.2)
			(layers "F.Cu" "F.Paste" "F.Mask")
			(roundrect_rratio 0.25)
			(net 46 "unconnected-(J1-Pad35)")
			(pintype "passive+no_connect")
		)
		(pad "36" smd roundrect
			(at 5.248 -2.15 270)
			(size 0.3 1.2)
			(layers "F.Cu" "F.Paste" "F.Mask")
			(roundrect_rratio 0.25)
			(net 47 "unconnected-(J1-Pad36)")
			(pintype "passive+no_connect")
		)
		(pad "37" smd roundrect
			(at 5.749 -2.15 270)
			(size 0.3 1.2)
			(layers "F.Cu" "F.Paste" "F.Mask")
			(roundrect_rratio 0.25)
			(net 48 "unconnected-(J1-Pad37)")
			(pintype "passive+no_connect")
		)
		(pad "38" smd roundrect
			(at 6.249 -2.15 270)
			(size 0.3 1.2)
			(layers "F.Cu" "F.Paste" "F.Mask")
			(roundrect_rratio 0.25)
			(net 49 "unconnected-(J1-Pad38)")
			(pintype "passive+no_connect")
		)
		(pad "39" smd roundrect
			(at 6.749 -2.15 270)
			(size 0.3 1.2)
			(layers "F.Cu" "F.Paste" "F.Mask")
			(roundrect_rratio 0.25)
			(net 34 "/CSI Connector/SDA_CAM0")
			(pintype "passive")
		)
		(pad "40" smd roundrect
			(at 7.249 -2.15 270)
			(size 0.3 1.2)
			(layers "F.Cu" "F.Paste" "F.Mask")
			(roundrect_rratio 0.25)
			(net 35 "/CSI Connector/SCL_CAM0")
			(pintype "passive")
		)
		(pad "41" smd roundrect
			(at 7.749 -2.15 270)
			(size 0.3 1.2)
			(layers "F.Cu" "F.Paste" "F.Mask")
			(roundrect_rratio 0.25)
			(net 36 "/CSI Connector/SDA_CAM1")
			(pintype "passive")
		)
		(pad "42" smd roundrect
			(at 8.249 -2.15 270)
			(size 0.3 1.2)
			(layers "F.Cu" "F.Paste" "F.Mask")
			(roundrect_rratio 0.25)
			(net 37 "/CSI Connector/SCL_CAM1")
			(pintype "passive")
		)
		(pad "43" smd roundrect
			(at 8.749 -2.15 270)
			(size 0.3 1.2)
			(layers "F.Cu" "F.Paste" "F.Mask")
			(roundrect_rratio 0.25)
			(net 52 "unconnected-(J1-Pad43)")
			(pintype "passive+no_connect")
		)
		(pad "44" smd roundrect
			(at 9.249 -2.15 270)
			(size 0.3 1.2)
			(layers "F.Cu" "F.Paste" "F.Mask")
			(roundrect_rratio 0.25)
			(net 53 "unconnected-(J1-Pad44)")
			(pintype "passive+no_connect")
		)
		(pad "45" smd roundrect
			(at 9.749 -2.15 270)
			(size 0.3 1.2)
			(layers "F.Cu" "F.Paste" "F.Mask")
			(roundrect_rratio 0.25)
			(net 54 "unconnected-(J1-Pad45)")
			(pintype "passive+no_connect")
		)
		(pad "46" smd roundrect
			(at 10.249 -2.15 270)
			(size 0.3 1.2)
			(layers "F.Cu" "F.Paste" "F.Mask")
			(roundrect_rratio 0.25)
			(net 55 "unconnected-(J1-Pad46)")
			(pintype "passive+no_connect")
		)
		(pad "47" smd roundrect
			(at 10.749 -2.15 270)
			(size 0.3 1.2)
			(layers "F.Cu" "F.Paste" "F.Mask")
			(roundrect_rratio 0.25)
			(net 10 "+3V3")
			(pintype "passive")
		)
		(pad "48" smd roundrect
			(at 11.249 -2.15 270)
			(size 0.3 1.2)
			(layers "F.Cu" "F.Paste" "F.Mask")
			(roundrect_rratio 0.25)
			(net 10 "+3V3")
			(pintype "passive")
		)
		(pad "49" smd roundrect
			(at 11.749 -2.15 270)
			(size 0.3 1.2)
			(layers "F.Cu" "F.Paste" "F.Mask")
			(roundrect_rratio 0.25)
			(net 9 "+5V")
			(pintype "passive")
		)
		(pad "50" smd roundrect
			(at 12.249 -2.15 270)
			(size 0.3 1.2)
			(layers "F.Cu" "F.Paste" "F.Mask")
			(roundrect_rratio 0.25)
			(net 9 "+5V")
			(pintype "passive")
		)
		(pad "MP1" smd roundrect
			(at -14.198 -0.3 270)
			(size 2.7 3)
			(layers "F.Cu" "F.Paste" "F.Mask")
			(roundrect_rratio 0.05)
			(net 1 "GND")
			(pinfunction "MP")
			(pintype "passive")
		)
		(pad "MP2" smd roundrect
			(at 14.198 -0.3 270)
			(size 2.7 3)
			(layers "F.Cu" "F.Paste" "F.Mask")
			(roundrect_rratio 0.05)
			(net 1 "GND")
			(pinfunction "MP")
			(pintype "passive")
		)
	)
	(footprint "antmicro-footprints:C_0402_1005Metric"
		(layer "F.Cu")
		(at 150.22 96.22 -45)
		(descr "Capacitor SMD 0402")
		(tags "capacitor SMD 0402")
		(property "Reference" "C18"
			(at 0.954594 -2.439518 -45)
			(unlocked yes)
			(layer "F.SilkS")
			(effects
				(font
					(size 0.7 0.7)
					(thickness 0.15)
				)
				(justify right bottom)
			)
		)
		(property "Value" "C_10u_0402"
			(at -1.022927 2.155213 135)
			(layer "F.Fab")
			(effects
				(font
					(size 0.7 0.7)
					(thickness 0.15)
				)
				(justify right bottom)
			)
		)
		(property "Footprint" "antmicro-footprints:C_0402_1005Metric"
			(at 0 0 -45)
			(layer "F.Fab")
			(hide yes)
			(effects
				(font
					(size 1.27 1.27)
					(thickness 0.15)
				)
			)
		)
		(property "Datasheet" "https://www.yageo.com/en/Chart/Download/pdf/CC0402MRX5R5BB106"
			(at 0 0 -45)
			(layer "F.Fab")
			(hide yes)
			(effects
				(font
					(size 1.27 1.27)
					(thickness 0.15)
				)
			)
		)
		(property "Author" "Antmicro"
			(at -24.039395 134.403766 0)
			(layer "F.Fab")
			(hide yes)
			(effects
				(font
					(size 1 1)
					(thickness 0.15)
				)
			)
		)
		(property "Dielectric" ""
			(at -24.039395 134.403766 0)
			(layer "F.Fab")
			(hide yes)
			(effects
				(font
					(size 1 1)
					(thickness 0.15)
				)
			)
		)
		(property "License" "Apache-2.0"
			(at -24.039395 134.403766 0)
			(layer "F.Fab")
			(hide yes)
			(effects
				(font
					(size 1 1)
					(thickness 0.15)
				)
			)
		)
		(property "MPN" "CC0402MRX5R5BB106"
			(at -24.039395 134.403766 0)
			(layer "F.Fab")
			(hide yes)
			(effects
				(font
					(size 1 1)
					(thickness 0.15)
				)
			)
		)
		(property "Manufacturer" "YAGEO"
			(at -24.039395 134.403766 0)
			(layer "F.Fab")
			(hide yes)
			(effects
				(font
					(size 1 1)
					(thickness 0.15)
				)
			)
		)
		(property "Val" "10u"
			(at -24.039395 134.403766 0)
			(layer "F.Fab")
			(hide yes)
			(effects
				(font
					(size 1 1)
					(thickness 0.15)
				)
			)
		)
		(property "Voltage" ""
			(at -24.039395 134.403766 0)
			(layer "F.Fab")
			(hide yes)
			(effects
				(font
					(size 1 1)
					(thickness 0.15)
				)
			)
		)
		(sheetname "Serializer")
		(sheetfile "serializer.kicad_sch")
		(attr smd)
		(fp_poly
			(pts
				(xy -0.925 -0.47) (xy 0.925 -0.47) (xy 0.925 0.47) (xy -0.925 0.47)
			)
			(stroke
				(width 0.05)
				(type default)
			)
			(fill none)
			(layer "F.CrtYd")
		)
		(fp_line
			(start -0.494 0.248)
			(end -0.494 -0.25)
			(stroke
				(width 0.15)
				(type solid)
			)
			(layer "F.Fab")
		)
		(fp_line
			(start -0.494 -0.25)
			(end 0.504 -0.25)
			(stroke
				(width 0.15)
				(type solid)
			)
			(layer "F.Fab")
		)
		(fp_line
			(start 0.504 0.248)
			(end -0.494 0.248)
			(stroke
				(width 0.15)
				(type solid)
			)
			(layer "F.Fab")
		)
		(fp_line
			(start 0.504 -0.25)
			(end 0.504 0.248)
			(stroke
				(width 0.15)
				(type solid)
			)
			(layer "F.Fab")
		)
		(fp_text user "${REFERENCE}"
			(at -0.939 4.599 135)
			(layer "F.Fab")
			(hide yes)
			(effects
				(font
					(size 0.7 0.7)
					(thickness 0.15)
				)
				(justify right bottom)
			)
		)
		(fp_text user "License: Apache-2.0"
			(at -0.939 5.799 135)
			(layer "F.Fab")
			(hide yes)
			(effects
				(font
					(size 0.7 0.7)
					(thickness 0.15)
				)
				(justify right bottom)
			)
		)
		(fp_text user "Author: Antmicro"
			(at -0.939 3.399 135)
			(layer "F.Fab")
			(hide yes)
			(effects
				(font
					(size 0.7 0.7)
					(thickness 0.15)
				)
				(justify right bottom)
			)
		)
		(pad "1" smd roundrect
			(at -0.48 0 315)
			(size 0.59 0.64)
			(layers "F.Cu" "F.Paste" "F.Mask")
			(roundrect_rratio 0.25)
			(net 1 "GND")
			(pintype "passive")
		)
		(pad "2" smd roundrect
			(at 0.48 0 315)
			(size 0.59 0.64)
			(layers "F.Cu" "F.Paste" "F.Mask")
			(roundrect_rratio 0.25)
			(net 12 "+1V2")
			(pintype "passive")
		)
	)
)
